(kicad_pcb
	(version 20260206)
	(generator "pcbnew")
	(generator_version "10.0")
	(general
		(thickness 1.6)
		(legacy_teardrops no)
	)
	(paper "A4")
	(title_block
		(title "Bryce Canyon_SCC_16316-1_OCP.brd")
		(comment 1 "Bryce Canyon / footprints 976-983 of 1561")
	)
	(layers
		(0 "F.Cu" signal "TOP")
		(4 "In1.Cu" signal "L2GND")
		(6 "In2.Cu" signal "L3")
		(8 "In3.Cu" signal "L4VCC")
		(10 "In4.Cu" signal "L5VCC")
		(12 "In5.Cu" signal "L6")
		(14 "In6.Cu" signal "L7GND")
		(2 "B.Cu" signal "BOTTOM")
		(9 "F.Adhes" user "F.Adhesive")
		(11 "B.Adhes" user "B.Adhesive")
		(13 "F.Paste" user "Package Geometry/Pastemask Top")
		(15 "B.Paste" user "Package Geometry/Pastemask Bottom")
		(5 "F.SilkS" user "Ref Des/Silkscreen Top")
		(7 "B.SilkS" user "Ref Des/Silkscreen Bottom")
		(1 "F.Mask" user "Board Geometry/Soldermask Top")
		(3 "B.Mask" user "Board Geometry/Soldermask Bottom")
		(17 "Dwgs.User" user "User.Drawings")
		(19 "Cmts.User" user "User.Comments")
		(21 "Eco1.User" user "User.Eco1")
		(23 "Eco2.User" user "User.Eco2")
		(25 "Edge.Cuts" user "Board Geometry/Outline")
		(27 "Margin" user)
		(31 "F.CrtYd" user "Package Geometry/Place Bound Top")
		(29 "B.CrtYd" user "Package Geometry/Place Bound Bottom")
		(35 "F.Fab" user "Ref Des/Assembly Top")
		(33 "B.Fab" user "Ref Des/Assembly Bottom")
	)
	(footprint ""
		(layer "B.Cu")
		(at 62.1792 -52.8574 -90)
		(property "Reference" "C684"
			(at 0 0 90)
			(layer "B.SilkS")
			(hide yes)
			(effects
				(font
					(size 1.27 1.27)
				)
				(justify mirror)
			)
		)
		(property "Value" "SC10U6D3V5KX-4GP"
			(at 0.0762 -6.1214 270)
			(unlocked yes)
			(layer "B.Fab")
			(hide yes)
			(effects
				(font
					(size 1.016 1.016)
					(thickness 0.1524)
				)
				(justify mirror)
			)
		)
		(property "Device Type" "C805H58"
			(at 0.0762 -8.1534 270)
			(unlocked yes)
			(layer "B.Fab")
			(hide yes)
			(effects
				(font
					(size 1.016 1.016)
					(thickness 0.1524)
				)
				(justify mirror)
			)
		)
		(duplicate_pad_numbers_are_jumpers no)
		(fp_line
			(start -0.635 0)
			(end 0.635 0)
			(stroke
				(width 0.508)
				(type default)
			)
			(layer "B.SilkS")
		)
		(fp_rect
			(start 0.9652 1.778)
			(end -0.9652 -1.778)
			(stroke
				(width 0)
				(type default)
			)
			(fill no)
			(layer "B.CrtYd")
		)
		(fp_poly
			(pts
				(xy 0.9652 -1.778) (xy -0.9652 -1.778) (xy -0.9652 1.778) (xy 0.9652 1.778)
			)
			(stroke
				(width 0)
				(type default)
			)
			(fill no)
			(layer "B.Fab")
		)
		(pad "1" smd rect
			(at 0 -0.9652 90)
			(size 1.397 1.143)
			(layers "B.Cu" "B.Mask" "B.Paste")
			(net "P0V9")
		)
		(pad "2" smd rect
			(at 0 0.9652 90)
			(size 1.397 1.143)
			(layers "B.Cu" "B.Mask" "B.Paste")
			(net "GND")
		)
	)
	(footprint ""
		(layer "B.Cu")
		(at 174.625 -70.739 180)
		(property "Reference" "Q8"
			(at 0 0 0)
			(layer "B.SilkS")
			(hide yes)
			(effects
				(font
					(size 1.27 1.27)
				)
				(justify mirror)
			)
		)
		(property "Value" "2N7002K-1-GP"
			(at -0.127 -8.9662 180)
			(unlocked yes)
			(layer "B.Fab")
			(hide yes)
			(effects
				(font
					(size 1.016 1.016)
					(thickness 0.1524)
				)
				(justify mirror)
			)
		)
		(property "Device Type" "SOT23DGS2D4H44"
			(at -0.127 -10.4902 180)
			(unlocked yes)
			(layer "B.Fab")
			(hide yes)
			(effects
				(font
					(size 1.016 1.016)
					(thickness 0.1524)
				)
				(justify mirror)
			)
		)
		(duplicate_pad_numbers_are_jumpers no)
		(fp_line
			(start 1.651 1.778)
			(end -1.651 1.778)
			(stroke
				(width 0.1524)
				(type default)
			)
			(layer "B.SilkS")
		)
		(fp_line
			(start 1.651 -1.778)
			(end 1.651 1.778)
			(stroke
				(width 0.1524)
				(type default)
			)
			(layer "B.SilkS")
		)
		(fp_line
			(start -1.651 1.778)
			(end -1.651 -1.778)
			(stroke
				(width 0.1524)
				(type default)
			)
			(layer "B.SilkS")
		)
		(fp_line
			(start -1.651 -1.778)
			(end 1.651 -1.778)
			(stroke
				(width 0.1524)
				(type default)
			)
			(layer "B.SilkS")
		)
		(fp_poly
			(pts
				(xy 1.778 1.8796) (xy 1.778 -1.8796) (xy -1.778 -1.8796) (xy -1.778 1.8796)
			)
			(stroke
				(width 0)
				(type default)
			)
			(fill no)
			(layer "B.CrtYd")
		)
		(fp_poly
			(pts
				(xy 1.778 1.8796) (xy 1.778 -1.8796) (xy -1.778 -1.8796) (xy -1.778 1.8796)
			)
			(stroke
				(width 0)
				(type default)
			)
			(fill no)
			(layer "B.Fab")
		)
		(pad "D" smd custom
			(at 0 -0.9525)
			(size 0.1905 0.1905)
			(layers "B.Cu" "B.Mask" "B.Paste")
			(net "SYS_RST_Q8")
			(options
				(clearance outline)
				(anchor circle)
			)
			(primitives
				(gr_poly
					(pts
						(arc
							(start -0.1778 -0.5715)
							(mid -0.321484 -0.511984)
							(end -0.381 -0.3683)
						)
						(arc
							(start -0.381 0.3683)
							(mid -0.321484 0.511984)
							(end -0.1778 0.5715)
						)
						(arc
							(start 0.1778 0.5715)
							(mid 0.321484 0.511984)
							(end 0.381 0.3683)
						)
						(arc
							(start 0.381 -0.3683)
							(mid 0.321484 -0.511984)
							(end 0.1778 -0.5715)
						)
					)
					(width 0)
					(fill yes)
				)
			)
		)
		(pad "G" smd custom
			(at 0.98425 0.9525)
			(size 0.1905 0.1905)
			(layers "B.Cu" "B.Mask" "B.Paste")
			(net "P3V3_STBY_Q15_R")
			(options
				(clearance outline)
				(anchor circle)
			)
			(primitives
				(gr_poly
					(pts
						(arc
							(start -0.1778 -0.5715)
							(mid -0.321484 -0.511984)
							(end -0.381 -0.3683)
						)
						(arc
							(start -0.381 0.3683)
							(mid -0.321484 0.511984)
							(end -0.1778 0.5715)
						)
						(arc
							(start 0.1778 0.5715)
							(mid 0.321484 0.511984)
							(end 0.381 0.3683)
						)
						(arc
							(start 0.381 -0.3683)
							(mid 0.321484 -0.511984)
							(end 0.1778 -0.5715)
						)
					)
					(width 0)
					(fill yes)
				)
			)
		)
		(pad "S" smd custom
			(at -0.98425 0.9525)
			(size 0.1905 0.1905)
			(layers "B.Cu" "B.Mask" "B.Paste")
			(net "GND")
			(options
				(clearance outline)
				(anchor circle)
			)
			(primitives
				(gr_poly
					(pts
						(arc
							(start -0.1778 -0.5715)
							(mid -0.321484 -0.511984)
							(end -0.381 -0.3683)
						)
						(arc
							(start -0.381 0.3683)
							(mid -0.321484 0.511984)
							(end -0.1778 0.5715)
						)
						(arc
							(start 0.1778 0.5715)
							(mid 0.321484 0.511984)
							(end 0.381 0.3683)
						)
						(arc
							(start 0.381 -0.3683)
							(mid 0.321484 -0.511984)
							(end 0.1778 -0.5715)
						)
					)
					(width 0)
					(fill yes)
				)
			)
		)
	)
	(footprint ""
		(layer "B.Cu")
		(at 172.122338 -42.91965 -90)
		(property "Reference" "C437"
			(at 0 0 90)
			(layer "B.SilkS")
			(hide yes)
			(effects
				(font
					(size 1.27 1.27)
				)
				(justify mirror)
			)
		)
		(property "Value" "SCD1U6D3V1KX-GP"
			(at 2.8321 -1.7399 270)
			(unlocked yes)
			(layer "B.Fab")
			(hide yes)
			(effects
				(font
					(size 1.016 1.016)
					(thickness 0.1524)
				)
				(justify mirror)
			)
		)
		(property "Device Type" "C0201H13"
			(at 2.8321 -3.2639 270)
			(unlocked yes)
			(layer "B.Fab")
			(hide yes)
			(effects
				(font
					(size 1.016 1.016)
					(thickness 0.1524)
				)
				(justify mirror)
			)
		)
		(duplicate_pad_numbers_are_jumpers no)
		(fp_rect
			(start 0.2794 0.6477)
			(end -0.2794 -0.6477)
			(stroke
				(width 0)
				(type default)
			)
			(fill no)
			(layer "B.CrtYd")
		)
		(fp_rect
			(start 0.2794 0.6477)
			(end -0.2794 -0.6477)
			(stroke
				(width 0)
				(type default)
			)
			(fill no)
			(layer "B.Fab")
		)
		(pad "1" smd custom
			(at 0 -0.2794 90)
			(size 0.0762 0.0762)
			(layers "B.Cu" "B.Mask" "B.Paste")
			(net "P0V975")
			(options
				(clearance outline)
				(anchor circle)
			)
			(primitives
				(gr_poly
					(pts
						(arc
							(start 0.1524 0.127)
							(mid 0.137521 0.162921)
							(end 0.1016 0.1778)
						)
						(arc
							(start -0.1016 0.1778)
							(mid -0.137521 0.162921)
							(end -0.1524 0.127)
						)
						(arc
							(start -0.1524 -0.127)
							(mid -0.137521 -0.162921)
							(end -0.1016 -0.1778)
						)
						(arc
							(start 0.1016 -0.1778)
							(mid 0.137521 -0.162921)
							(end 0.1524 -0.127)
						)
					)
					(width 0)
					(fill yes)
				)
			)
		)
		(pad "2" smd custom
			(at 0 0.2794 90)
			(size 0.0762 0.0762)
			(layers "B.Cu" "B.Mask" "B.Paste")
			(net "GND")
			(options
				(clearance outline)
				(anchor circle)
			)
			(primitives
				(gr_poly
					(pts
						(arc
							(start 0.1524 0.127)
							(mid 0.137521 0.162921)
							(end 0.1016 0.1778)
						)
						(arc
							(start -0.1016 0.1778)
							(mid -0.137521 0.162921)
							(end -0.1524 0.127)
						)
						(arc
							(start -0.1524 -0.127)
							(mid -0.137521 -0.162921)
							(end -0.1016 -0.1778)
						)
						(arc
							(start 0.1016 -0.1778)
							(mid 0.137521 -0.162921)
							(end 0.1524 -0.127)
						)
					)
					(width 0)
					(fill yes)
				)
			)
		)
	)
	(footprint ""
		(layer "B.Cu")
		(at 122.530108 -59.455812)
		(property "Reference" "C282"
			(at 0 0 0)
			(layer "B.SilkS")
			(hide yes)
			(effects
				(font
					(size 1.27 1.27)
				)
				(justify mirror)
			)
		)
		(property "Value" "SCD1U6D3V1KX-GP"
			(at 2.8321 -1.7399 0)
			(unlocked yes)
			(layer "B.Fab")
			(hide yes)
			(effects
				(font
					(size 1.016 1.016)
					(thickness 0.1524)
				)
				(justify mirror)
			)
		)
		(property "Device Type" "C0201H13"
			(at 2.8321 -3.2639 0)
			(unlocked yes)
			(layer "B.Fab")
			(hide yes)
			(effects
				(font
					(size 1.016 1.016)
					(thickness 0.1524)
				)
				(justify mirror)
			)
		)
		(duplicate_pad_numbers_are_jumpers no)
		(fp_rect
			(start 0.2794 0.6477)
			(end -0.2794 -0.6477)
			(stroke
				(width 0)
				(type default)
			)
			(fill no)
			(layer "B.CrtYd")
		)
		(fp_rect
			(start 0.2794 0.6477)
			(end -0.2794 -0.6477)
			(stroke
				(width 0)
				(type default)
			)
			(fill no)
			(layer "B.Fab")
		)
		(pad "1" smd custom
			(at 0 -0.2794 180)
			(size 0.0762 0.0762)
			(layers "B.Cu" "B.Mask" "B.Paste")
			(net "GB_VDDA")
			(options
				(clearance outline)
				(anchor circle)
			)
			(primitives
				(gr_poly
					(pts
						(arc
							(start 0.1524 0.127)
							(mid 0.137521 0.162921)
							(end 0.1016 0.1778)
						)
						(arc
							(start -0.1016 0.1778)
							(mid -0.137521 0.162921)
							(end -0.1524 0.127)
						)
						(arc
							(start -0.1524 -0.127)
							(mid -0.137521 -0.162921)
							(end -0.1016 -0.1778)
						)
						(arc
							(start 0.1016 -0.1778)
							(mid 0.137521 -0.162921)
							(end 0.1524 -0.127)
						)
					)
					(width 0)
					(fill yes)
				)
			)
		)
		(pad "2" smd custom
			(at 0 0.2794 180)
			(size 0.0762 0.0762)
			(layers "B.Cu" "B.Mask" "B.Paste")
			(net "GND")
			(options
				(clearance outline)
				(anchor circle)
			)
			(primitives
				(gr_poly
					(pts
						(arc
							(start 0.1524 0.127)
							(mid 0.137521 0.162921)
							(end 0.1016 0.1778)
						)
						(arc
							(start -0.1016 0.1778)
							(mid -0.137521 0.162921)
							(end -0.1524 0.127)
						)
						(arc
							(start -0.1524 -0.127)
							(mid -0.137521 -0.162921)
							(end -0.1016 -0.1778)
						)
						(arc
							(start 0.1016 -0.1778)
							(mid 0.137521 -0.162921)
							(end 0.1524 -0.127)
						)
					)
					(width 0)
					(fill yes)
				)
			)
		)
	)
	(footprint ""
		(layer "B.Cu")
		(at 108.5342 -64.516 -90)
		(property "Reference" "C157"
			(at 0 0 90)
			(layer "B.SilkS")
			(hide yes)
			(effects
				(font
					(size 1.27 1.27)
				)
				(justify mirror)
			)
		)
		(property "Value" "SCD1U6D3V1KX-GP"
			(at 2.8321 -1.7399 270)
			(unlocked yes)
			(layer "B.Fab")
			(hide yes)
			(effects
				(font
					(size 1.016 1.016)
					(thickness 0.1524)
				)
				(justify mirror)
			)
		)
		(property "Device Type" "C0201H13"
			(at 2.8321 -3.2639 270)
			(unlocked yes)
			(layer "B.Fab")
			(hide yes)
			(effects
				(font
					(size 1.016 1.016)
					(thickness 0.1524)
				)
				(justify mirror)
			)
		)
		(duplicate_pad_numbers_are_jumpers no)
		(fp_rect
			(start 0.2794 0.6477)
			(end -0.2794 -0.6477)
			(stroke
				(width 0)
				(type default)
			)
			(fill no)
			(layer "B.CrtYd")
		)
		(fp_rect
			(start 0.2794 0.6477)
			(end -0.2794 -0.6477)
			(stroke
				(width 0)
				(type default)
			)
			(fill no)
			(layer "B.Fab")
		)
		(pad "1" smd custom
			(at 0 -0.2794 90)
			(size 0.0762 0.0762)
			(layers "B.Cu" "B.Mask" "B.Paste")
			(net "P1V8_E")
			(options
				(clearance outline)
				(anchor circle)
			)
			(primitives
				(gr_poly
					(pts
						(arc
							(start 0.1524 0.127)
							(mid 0.137521 0.162921)
							(end 0.1016 0.1778)
						)
						(arc
							(start -0.1016 0.1778)
							(mid -0.137521 0.162921)
							(end -0.1524 0.127)
						)
						(arc
							(start -0.1524 -0.127)
							(mid -0.137521 -0.162921)
							(end -0.1016 -0.1778)
						)
						(arc
							(start 0.1016 -0.1778)
							(mid 0.137521 -0.162921)
							(end 0.1524 -0.127)
						)
					)
					(width 0)
					(fill yes)
				)
			)
		)
		(pad "2" smd custom
			(at 0 0.2794 90)
			(size 0.0762 0.0762)
			(layers "B.Cu" "B.Mask" "B.Paste")
			(net "GND")
			(options
				(clearance outline)
				(anchor circle)
			)
			(primitives
				(gr_poly
					(pts
						(arc
							(start 0.1524 0.127)
							(mid 0.137521 0.162921)
							(end 0.1016 0.1778)
						)
						(arc
							(start -0.1016 0.1778)
							(mid -0.137521 0.162921)
							(end -0.1524 0.127)
						)
						(arc
							(start -0.1524 -0.127)
							(mid -0.137521 -0.162921)
							(end -0.1016 -0.1778)
						)
						(arc
							(start 0.1016 -0.1778)
							(mid 0.137521 -0.162921)
							(end 0.1524 -0.127)
						)
					)
					(width 0)
					(fill yes)
				)
			)
		)
	)
	(footprint ""
		(layer "B.Cu")
		(at 173.8122 -39.9669 -90)
		(property "Reference" "C444"
			(at 0 0 90)
			(layer "B.SilkS")
			(hide yes)
			(effects
				(font
					(size 1.27 1.27)
				)
				(justify mirror)
			)
		)
		(property "Value" "SC1KP50V2KX-1GP"
			(at -1.1811 -2.7051 270)
			(unlocked yes)
			(layer "B.Fab")
			(hide yes)
			(effects
				(font
					(size 1.016 1.016)
					(thickness 0.1524)
				)
				(justify mirror)
			)
		)
		(property "Device Type" "C402H22"
			(at -1.1811 -4.2291 270)
			(unlocked yes)
			(layer "B.Fab")
			(hide yes)
			(effects
				(font
					(size 1.016 1.016)
					(thickness 0.1524)
				)
				(justify mirror)
			)
		)
		(duplicate_pad_numbers_are_jumpers no)
		(fp_rect
			(start 0.4318 0.9525)
			(end -0.4318 -0.9525)
			(stroke
				(width 0)
				(type default)
			)
			(fill no)
			(layer "B.CrtYd")
		)
		(fp_rect
			(start 0.4318 0.9525)
			(end -0.4318 -0.9525)
			(stroke
				(width 0)
				(type default)
			)
			(fill no)
			(layer "B.Fab")
		)
		(pad "1" smd custom
			(at 0 -0.4445 90)
			(size 0.1524 0.1524)
			(layers "B.Cu" "B.Mask" "B.Paste")
			(net "P0V975")
			(options
				(clearance outline)
				(anchor circle)
			)
			(primitives
				(gr_poly
					(pts
						(arc
							(start 0.3048 0.2032)
							(mid 0.275042 0.275042)
							(end 0.2032 0.3048)
						)
						(arc
							(start -0.2032 0.3048)
							(mid -0.275042 0.275042)
							(end -0.3048 0.2032)
						)
						(arc
							(start -0.3048 -0.2032)
							(mid -0.275042 -0.275042)
							(end -0.2032 -0.3048)
						)
						(arc
							(start 0.2032 -0.3048)
							(mid 0.275042 -0.275042)
							(end 0.3048 -0.2032)
						)
					)
					(width 0)
					(fill yes)
				)
			)
		)
		(pad "2" smd custom
			(at 0 0.4445 90)
			(size 0.1524 0.1524)
			(layers "B.Cu" "B.Mask" "B.Paste")
			(net "GND")
			(options
				(clearance outline)
				(anchor circle)
			)
			(primitives
				(gr_poly
					(pts
						(arc
							(start 0.3048 0.2032)
							(mid 0.275042 0.275042)
							(end 0.2032 0.3048)
						)
						(arc
							(start -0.2032 0.3048)
							(mid -0.275042 0.275042)
							(end -0.3048 0.2032)
						)
						(arc
							(start -0.3048 -0.2032)
							(mid -0.275042 -0.275042)
							(end -0.2032 -0.3048)
						)
						(arc
							(start 0.2032 -0.3048)
							(mid 0.275042 -0.275042)
							(end 0.3048 -0.2032)
						)
					)
					(width 0)
					(fill yes)
				)
			)
		)
	)
	(footprint ""
		(layer "B.Cu")
		(at 183.668416 -87.639652 90)
		(property "Reference" "C629"
			(at 0 0 90)
			(layer "B.SilkS")
			(hide yes)
			(effects
				(font
					(size 1.27 1.27)
				)
				(justify mirror)
			)
		)
		(property "Value" "SC10U6D3V5KX-4GP"
			(at 0.0762 -6.1214 90)
			(unlocked yes)
			(layer "B.Fab")
			(hide yes)
			(effects
				(font
					(size 1.016 1.016)
					(thickness 0.1524)
				)
				(justify mirror)
			)
		)
		(property "Device Type" "C805H58"
			(at 0.0762 -8.1534 90)
			(unlocked yes)
			(layer "B.Fab")
			(hide yes)
			(effects
				(font
					(size 1.016 1.016)
					(thickness 0.1524)
				)
				(justify mirror)
			)
		)
		(duplicate_pad_numbers_are_jumpers no)
		(fp_line
			(start -0.635 0)
			(end 0.635 0)
			(stroke
				(width 0.508)
				(type default)
			)
			(layer "B.SilkS")
		)
		(fp_rect
			(start 0.9652 1.778)
			(end -0.9652 -1.778)
			(stroke
				(width 0)
				(type default)
			)
			(fill no)
			(layer "B.CrtYd")
		)
		(fp_poly
			(pts
				(xy 0.9652 -1.778) (xy -0.9652 -1.778) (xy -0.9652 1.778) (xy 0.9652 1.778)
			)
			(stroke
				(width 0)
				(type default)
			)
			(fill no)
			(layer "B.Fab")
		)
		(pad "1" smd rect
			(at 0 -0.9652 270)
			(size 1.397 1.143)
			(layers "B.Cu" "B.Mask" "B.Paste")
			(net "P0V975")
		)
		(pad "2" smd rect
			(at 0 0.9652 270)
			(size 1.397 1.143)
			(layers "B.Cu" "B.Mask" "B.Paste")
			(net "GND")
		)
	)
	(footprint ""
		(layer "B.Cu")
		(at 82.622898 -70.40118)
		(property "Reference" "C515"
			(at 0 0 0)
			(layer "B.SilkS")
			(hide yes)
			(effects
				(font
					(size 1.27 1.27)
				)
				(justify mirror)
			)
		)
		(property "Value" "SCD1U16V2KX-3GP"
			(at -1.1811 -2.7051 0)
			(unlocked yes)
			(layer "B.Fab")
			(hide yes)
			(effects
				(font
					(size 1.016 1.016)
					(thickness 0.1524)
				)
				(justify mirror)
			)
		)
		(property "Device Type" "C402H22"
			(at -1.1811 -4.2291 0)
			(unlocked yes)
			(layer "B.Fab")
			(hide yes)
			(effects
				(font
					(size 1.016 1.016)
					(thickness 0.1524)
				)
				(justify mirror)
			)
		)
		(duplicate_pad_numbers_are_jumpers no)
		(fp_rect
			(start 0.4318 0.9525)
			(end -0.4318 -0.9525)
			(stroke
				(width 0)
				(type default)
			)
			(fill no)
			(layer "B.CrtYd")
		)
		(fp_rect
			(start 0.4318 0.9525)
			(end -0.4318 -0.9525)
			(stroke
				(width 0)
				(type default)
			)
			(fill no)
			(layer "B.Fab")
		)
		(pad "1" smd custom
			(at 0 -0.4445 180)
			(size 0.1524 0.1524)
			(layers "B.Cu" "B.Mask" "B.Paste")
			(net "P3V3")
			(options
				(clearance outline)
				(anchor circle)
			)
			(primitives
				(gr_poly
					(pts
						(arc
							(start 0.3048 0.2032)
							(mid 0.275042 0.275042)
							(end 0.2032 0.3048)
						)
						(arc
							(start -0.2032 0.3048)
							(mid -0.275042 0.275042)
							(end -0.3048 0.2032)
						)
						(arc
							(start -0.3048 -0.2032)
							(mid -0.275042 -0.275042)
							(end -0.2032 -0.3048)
						)
						(arc
							(start 0.2032 -0.3048)
							(mid 0.275042 -0.275042)
							(end 0.3048 -0.2032)
						)
					)
					(width 0)
					(fill yes)
				)
			)
		)
		(pad "2" smd custom
			(at 0 0.4445 180)
			(size 0.1524 0.1524)
			(layers "B.Cu" "B.Mask" "B.Paste")
			(net "GND")
			(options
				(clearance outline)
				(anchor circle)
			)
			(primitives
				(gr_poly
					(pts
						(arc
							(start 0.3048 0.2032)
							(mid 0.275042 0.275042)
							(end 0.2032 0.3048)
						)
						(arc
							(start -0.2032 0.3048)
							(mid -0.275042 0.275042)
							(end -0.3048 0.2032)
						)
						(arc
							(start -0.3048 -0.2032)
							(mid -0.275042 -0.275042)
							(end -0.2032 -0.3048)
						)
						(arc
							(start 0.2032 -0.3048)
							(mid 0.275042 -0.275042)
							(end 0.3048 -0.2032)
						)
					)
					(width 0)
					(fill yes)
				)
			)
		)
	)
)
